(kicad_pcb
	(version 20260206)
	(generator "pcbnew")
	(generator_version "10.0")
	(general
		(thickness 1.6)
		(legacy_teardrops no)
	)
	(paper "A4")
	(title_block
		(title "Wiwynn_Tioga_Pass_MB.brd")
		(comment 1 "Tioga Pass / footprints 449-454 of 4770")
	)
	(layers
		(0 "F.Cu" signal "TOP")
		(4 "In1.Cu" signal "L2GND")
		(6 "In2.Cu" signal "L3")
		(8 "In3.Cu" signal "L4GND")
		(10 "In4.Cu" signal "L5")
		(12 "In5.Cu" signal "L6GND")
		(14 "In6.Cu" signal "L7VCC")
		(16 "In7.Cu" signal "L8VCC")
		(18 "In8.Cu" signal "L9GND")
		(20 "In9.Cu" signal "L10")
		(22 "In10.Cu" signal "L11GND")
		(24 "In11.Cu" signal "L12")
		(26 "In12.Cu" signal "L13GND")
		(2 "B.Cu" signal "BOTTOM")
		(9 "F.Adhes" user "F.Adhesive")
		(11 "B.Adhes" user "B.Adhesive")
		(13 "F.Paste" user "Package Geometry/Pastemask Top")
		(15 "B.Paste" user "Package Geometry/Pastemask Bottom")
		(5 "F.SilkS" user "Ref Des/Silkscreen Top")
		(7 "B.SilkS" user "Ref Des/Silkscreen Bottom")
		(1 "F.Mask" user "Board Geometry/Soldermask Top")
		(3 "B.Mask" user "Board Geometry/Soldermask Bottom")
		(17 "Dwgs.User" user "User.Drawings")
		(19 "Cmts.User" user "User.Comments")
		(21 "Eco1.User" user "User.Eco1")
		(23 "Eco2.User" user "User.Eco2")
		(25 "Edge.Cuts" user "Board Geometry/Outline")
		(27 "Margin" user)
		(31 "F.CrtYd" user "Package Geometry/Place Bound Top")
		(29 "B.CrtYd" user "Package Geometry/Place Bound Bottom")
		(35 "F.Fab" user "Ref Des/Assembly Top")
		(33 "B.Fab" user "Ref Des/Assembly Bottom")
	)
	(footprint ""
		(layer "F.Cu")
		(at 382.27 3.81 90)
		(property "Reference" "J7G2"
			(at 3.02133 18.669 0)
			(unlocked yes)
			(layer "F.SilkS")
			(effects
				(font
					(size 0.7874 0.5842)
					(thickness 0.1524)
				)
			)
		)
		(property "Value" ""
			(at 0 0 90)
			(layer "F.Fab")
			(effects
				(font
					(size 1.27 1.27)
				)
			)
		)
		(duplicate_pad_numbers_are_jumpers no)
		(fp_line
			(start 1.2954 -1.27)
			(end 1.2954 19.05)
			(stroke
				(width 0.1524)
				(type default)
			)
			(layer "F.SilkS")
		)
		(fp_line
			(start -1.2954 -1.27)
			(end 1.2954 -1.27)
			(stroke
				(width 0.1524)
				(type default)
			)
			(layer "F.SilkS")
		)
		(fp_line
			(start 1.2954 19.05)
			(end -1.2954 19.05)
			(stroke
				(width 0.1524)
				(type default)
			)
			(layer "F.SilkS")
		)
		(fp_line
			(start -1.2954 19.05)
			(end -1.2954 -1.27)
			(stroke
				(width 0.1524)
				(type default)
			)
			(layer "F.SilkS")
		)
		(fp_poly
			(pts
				(xy 1.070356 -0.705866) (xy 2.340356 -1.213866) (xy 2.340356 -0.197866)
			)
			(stroke
				(width 0)
				(type default)
			)
			(fill yes)
			(layer "F.SilkS")
		)
		(fp_poly
			(pts
				(xy 1.4732 0.0254) (xy 2.7432 -0.4826) (xy 2.7432 0.5334)
			)
			(stroke
				(width 0)
				(type default)
			)
			(fill yes)
			(layer "B.SilkS")
		)
		(fp_poly
			(pts
				(xy -1.2954 19.05) (xy 1.2954 19.05) (xy 1.2954 -1.27) (xy -1.2954 -1.27)
			)
			(stroke
				(width 0)
				(type default)
			)
			(fill no)
			(layer "F.CrtYd")
		)
		(fp_poly
			(pts
				(xy 1.4732 0.0254) (xy 2.7432 -0.4826) (xy 2.7432 0.5334)
			)
			(stroke
				(width 0)
				(type default)
			)
			(fill yes)
			(layer "B.Fab")
		)
		(fp_line
			(start 1.2954 -1.27)
			(end -1.2954 -1.27)
			(stroke
				(width 0.1)
				(type default)
			)
			(layer "F.Fab")
		)
		(fp_line
			(start -1.2954 -1.27)
			(end -1.2954 19.05)
			(stroke
				(width 0.1)
				(type default)
			)
			(layer "F.Fab")
		)
		(fp_line
			(start 1.2954 19.05)
			(end 1.2954 -1.27)
			(stroke
				(width 0.1)
				(type default)
			)
			(layer "F.Fab")
		)
		(fp_line
			(start -1.2954 19.05)
			(end 1.2954 19.05)
			(stroke
				(width 0.1)
				(type default)
			)
			(layer "F.Fab")
		)
		(fp_poly
			(pts
				(xy 1.4732 0.0254) (xy 2.7432 -0.4826) (xy 2.7432 0.5334)
			)
			(stroke
				(width 0)
				(type default)
			)
			(fill yes)
			(layer "F.Fab")
		)
		(fp_text user "8"
			(at 1.76911 19.26844 0)
			(unlocked yes)
			(layer "F.SilkS")
			(effects
				(font
					(size 0.7874 0.5842)
					(thickness 0.1524)
				)
			)
		)
		(fp_text user "8"
			(at 1.8288 17.85747 90)
			(unlocked yes)
			(layer "B.SilkS")
			(effects
				(font
					(size 0.7874 0.5842)
					(thickness 0.1524)
				)
			)
		)
		(fp_text user "8"
			(at 1.8288 17.85747 90)
			(unlocked yes)
			(layer "B.Fab")
			(effects
				(font
					(size 0.7874 0.5842)
					(thickness 0.1524)
				)
			)
		)
		(fp_text user "8"
			(at 0.218694 -1.651 0)
			(unlocked yes)
			(layer "F.Fab")
			(effects
				(font
					(size 0.7874 0.5842)
					(thickness 0.1524)
				)
			)
		)
		(pad "1" thru_hole rect
			(at 0 0 90)
			(size 1.6256 1.6256)
			(drill 1.2446)
			(layers "*.Cu" "*.Mask")
			(remove_unused_layers no)
			(net "P3V3_STBY_PLD_D")
			(clearance 0.127)
			(thermal_gap 0.127)
			(padstack
				(mode front_inner_back)
				(layer "Inner"
					(shape circle)
					(size 1.6256 1.6256)
					(clearance 0.127)
				)
				(layer "B.Cu"
					(shape rect)
					(size 1.6256 1.6256)
					(clearance 0.127)
				)
			)
		)
		(pad "2" thru_hole circle
			(at 0 2.54 90)
			(size 1.6256 1.6256)
			(drill 1.2446)
			(layers "*.Cu" "*.Mask")
			(remove_unused_layers no)
			(net "JTAG_TDO_R")
			(clearance 0.127)
			(thermal_gap 0.127)
		)
		(pad "3" thru_hole circle
			(at 0 5.08 90)
			(size 1.6256 1.6256)
			(drill 1.2446)
			(layers "*.Cu" "*.Mask")
			(remove_unused_layers no)
			(net "JTAG_TDI_R")
			(clearance 0.127)
			(thermal_gap 0.127)
		)
		(pad "4" thru_hole circle
			(at 0 7.62 90)
			(size 1.6256 1.6256)
			(drill 1.2446)
			(layers "*.Cu" "*.Mask")
			(remove_unused_layers no)
			(net "JTAG_TRST_N")
			(clearance 0.127)
			(thermal_gap 0.127)
		)
		(pad "5" thru_hole circle
			(at 0 10.16 90)
			(size 1.6256 1.6256)
			(drill 1.2446)
			(layers "*.Cu" "*.Mask")
			(remove_unused_layers no)
			(net "PWRGD_P3V3_STBY")
			(clearance 0.127)
			(thermal_gap 0.127)
		)
		(pad "6" thru_hole circle
			(at 0 12.7 90)
			(size 1.6256 1.6256)
			(drill 1.2446)
			(layers "*.Cu" "*.Mask")
			(remove_unused_layers no)
			(net "JTAG_TMS_R")
			(clearance 0.127)
			(thermal_gap 0.127)
		)
		(pad "7" thru_hole circle
			(at 0 15.24 90)
			(size 1.6256 1.6256)
			(drill 1.2446)
			(layers "*.Cu" "*.Mask")
			(remove_unused_layers no)
			(net "GND")
			(clearance 0.127)
			(thermal_gap 0.127)
		)
		(pad "8" thru_hole circle
			(at 0 17.78 90)
			(size 1.6256 1.6256)
			(drill 1.2446)
			(layers "*.Cu" "*.Mask")
			(remove_unused_layers no)
			(net "JTAG_TCK_R")
			(clearance 0.127)
			(thermal_gap 0.127)
		)
	)
	(footprint ""
		(layer "F.Cu")
		(at 393.1412 1.5748 90)
		(property "Reference" "R8G20"
			(at 0 0 90)
			(layer "F.SilkS")
			(hide yes)
			(effects
				(font
					(size 1.27 1.27)
				)
			)
		)
		(property "Value" ""
			(at 0 0 90)
			(layer "F.Fab")
			(effects
				(font
					(size 1.27 1.27)
				)
			)
		)
		(duplicate_pad_numbers_are_jumpers no)
		(fp_poly
			(pts
				(xy -0.2794 -0.1016) (xy 0.2794 -0.1016) (xy 0.2794 0.9906) (xy -0.2794 0.9906)
			)
			(stroke
				(width 0)
				(type default)
			)
			(fill no)
			(layer "F.CrtYd")
		)
		(fp_line
			(start 0.2794 -0.1016)
			(end -0.2794 -0.1016)
			(stroke
				(width 0.1)
				(type default)
			)
			(layer "F.Fab")
		)
		(fp_line
			(start -0.2794 -0.1016)
			(end -0.2794 0.9906)
			(stroke
				(width 0.1)
				(type default)
			)
			(layer "F.Fab")
		)
		(fp_line
			(start 0.2794 0.9906)
			(end 0.2794 -0.1016)
			(stroke
				(width 0.1)
				(type default)
			)
			(layer "F.Fab")
		)
		(fp_line
			(start -0.2794 0.9906)
			(end 0.2794 0.9906)
			(stroke
				(width 0.1)
				(type default)
			)
			(layer "F.Fab")
		)
		(pad "1" smd rect
			(at 0 0 90)
			(size 0.508 0.508)
			(layers "F.Cu" "F.Mask" "F.Paste")
			(net "P3V3_STBY")
		)
		(pad "2" smd rect
			(at 0 0.889 90)
			(size 0.508 0.508)
			(layers "F.Cu" "F.Mask" "F.Paste")
			(net "JTAG_TMS_R")
		)
		(zone
			(layer "F.Cu")
			(hatch none 0.5)
			(connect_pads
				(clearance 0)
			)
			(min_thickness 0.25)
			(keepout
				(tracks allowed)
				(vias not_allowed)
				(pads allowed)
				(copperpour not_allowed)
				(footprints allowed)
			)
			(placement
				(enabled no)
				(sheetname "")
			)
			(fill
				(thermal_gap 0.5)
				(thermal_bridge_width 0.5)
				(island_removal_mode 0)
			)
			(polygon
				(pts
					(xy 393.3952 1.8288) (xy 393.3952 1.3208) (xy 393.7762 1.3208) (xy 393.7762 1.8288)
				)
			)
		)
		(zone
			(layer "F.Cu")
			(hatch none 0.5)
			(connect_pads
				(clearance 0)
			)
			(min_thickness 0.25)
			(keepout
				(tracks not_allowed)
				(vias allowed)
				(pads allowed)
				(copperpour not_allowed)
				(footprints allowed)
			)
			(placement
				(enabled no)
				(sheetname "")
			)
			(fill
				(thermal_gap 0.5)
				(thermal_bridge_width 0.5)
				(island_removal_mode 0)
			)
			(polygon
				(pts
					(xy 393.7762 1.8288) (xy 393.7762 1.3208) (xy 393.3952 1.3208) (xy 393.3952 1.8288)
				)
			)
		)
	)
	(footprint ""
		(layer "F.Cu")
		(at 363.8804 -136.7536 90)
		(property "Reference" "R12W29"
			(at -0.8382 -0.67818 90)
			(unlocked yes)
			(layer "F.SilkS")
			(effects
				(font
					(size 0.4064 0.254)
					(thickness 0.1524)
				)
				(justify left)
			)
		)
		(property "Value" ""
			(at 0 0 90)
			(layer "F.Fab")
			(effects
				(font
					(size 1.27 1.27)
				)
			)
		)
		(duplicate_pad_numbers_are_jumpers no)
		(fp_poly
			(pts
				(xy -0.2794 -0.1016) (xy 0.2794 -0.1016) (xy 0.2794 0.9906) (xy -0.2794 0.9906)
			)
			(stroke
				(width 0)
				(type default)
			)
			(fill no)
			(layer "F.CrtYd")
		)
		(fp_line
			(start 0.2794 -0.1016)
			(end -0.2794 -0.1016)
			(stroke
				(width 0.1)
				(type default)
			)
			(layer "F.Fab")
		)
		(fp_line
			(start -0.2794 -0.1016)
			(end -0.2794 0.9906)
			(stroke
				(width 0.1)
				(type default)
			)
			(layer "F.Fab")
		)
		(fp_line
			(start 0.2794 0.9906)
			(end 0.2794 -0.1016)
			(stroke
				(width 0.1)
				(type default)
			)
			(layer "F.Fab")
		)
		(fp_line
			(start -0.2794 0.9906)
			(end 0.2794 0.9906)
			(stroke
				(width 0.1)
				(type default)
			)
			(layer "F.Fab")
		)
		(pad "1" smd rect
			(at 0 0 90)
			(size 0.508 0.508)
			(layers "F.Cu" "F.Mask" "F.Paste")
			(net "TP_PVDDQ_DEF_MP1")
		)
		(pad "2" smd rect
			(at 0 0.889 90)
			(size 0.508 0.508)
			(layers "F.Cu" "F.Mask" "F.Paste")
			(net "PWRGD_PVDDQ_DEF")
		)
		(zone
			(layer "F.Cu")
			(hatch none 0.5)
			(connect_pads
				(clearance 0)
			)
			(min_thickness 0.25)
			(keepout
				(tracks allowed)
				(vias not_allowed)
				(pads allowed)
				(copperpour not_allowed)
				(footprints allowed)
			)
			(placement
				(enabled no)
				(sheetname "")
			)
			(fill
				(thermal_gap 0.5)
				(thermal_bridge_width 0.5)
				(island_removal_mode 0)
			)
			(polygon
				(pts
					(xy 364.1344 -136.4996) (xy 364.1344 -137.0076) (xy 364.5154 -137.0076) (xy 364.5154 -136.4996)
				)
			)
		)
		(zone
			(layer "F.Cu")
			(hatch none 0.5)
			(connect_pads
				(clearance 0)
			)
			(min_thickness 0.25)
			(keepout
				(tracks not_allowed)
				(vias allowed)
				(pads allowed)
				(copperpour not_allowed)
				(footprints allowed)
			)
			(placement
				(enabled no)
				(sheetname "")
			)
			(fill
				(thermal_gap 0.5)
				(thermal_bridge_width 0.5)
				(island_removal_mode 0)
			)
			(polygon
				(pts
					(xy 364.5154 -136.4996) (xy 364.5154 -137.0076) (xy 364.1344 -137.0076) (xy 364.1344 -136.4996)
				)
			)
		)
	)
	(footprint ""
		(layer "F.Cu")
		(at 266.920472 -77.636116)
		(property "Reference" "C5D31"
			(at 0 0 0)
			(layer "F.SilkS")
			(hide yes)
			(effects
				(font
					(size 1.27 1.27)
				)
			)
		)
		(property "Value" ""
			(at 0 0 0)
			(layer "F.Fab")
			(effects
				(font
					(size 1.27 1.27)
				)
			)
		)
		(duplicate_pad_numbers_are_jumpers no)
		(fp_poly
			(pts
				(xy -0.4953 -0.2032) (xy 0.4953 -0.2032) (xy 0.4953 1.6002) (xy -0.4953 1.6002)
			)
			(stroke
				(width 0)
				(type default)
			)
			(fill no)
			(layer "F.CrtYd")
		)
		(fp_line
			(start -0.4953 -0.2032)
			(end 0.4953 -0.2032)
			(stroke
				(width 0.1)
				(type default)
			)
			(layer "F.Fab")
		)
		(fp_line
			(start -0.4953 1.6002)
			(end -0.4953 -0.2032)
			(stroke
				(width 0.1)
				(type default)
			)
			(layer "F.Fab")
		)
		(fp_line
			(start 0.4953 -0.2032)
			(end 0.4953 1.6002)
			(stroke
				(width 0.1)
				(type default)
			)
			(layer "F.Fab")
		)
		(fp_line
			(start 0.4953 1.6002)
			(end -0.4953 1.6002)
			(stroke
				(width 0.1)
				(type default)
			)
			(layer "F.Fab")
		)
		(pad "1" smd rect
			(at 0 0)
			(size 0.762 0.889)
			(layers "F.Cu" "F.Mask" "F.Paste")
			(net "PVCCIN_CPU0")
		)
		(pad "2" smd rect
			(at 0 1.397)
			(size 0.762 0.889)
			(layers "F.Cu" "F.Mask" "F.Paste")
			(net "GND")
		)
		(zone
			(layer "F.Cu")
			(hatch none 0.5)
			(connect_pads
				(clearance 0)
			)
			(min_thickness 0.25)
			(keepout
				(tracks not_allowed)
				(vias allowed)
				(pads allowed)
				(copperpour not_allowed)
				(footprints allowed)
			)
			(placement
				(enabled no)
				(sheetname "")
			)
			(fill
				(thermal_gap 0.5)
				(thermal_bridge_width 0.5)
				(island_removal_mode 0)
			)
			(polygon
				(pts
					(xy 266.539472 -77.191616) (xy 267.301472 -77.191616) (xy 267.301472 -76.683616) (xy 266.539472 -76.683616)
				)
			)
		)
	)
	(footprint ""
		(layer "F.Cu")
		(at 403.987 -115.697 90)
		(property "Reference" "R25W140"
			(at -0.8382 -0.67818 90)
			(unlocked yes)
			(layer "F.SilkS")
			(effects
				(font
					(size 0.4064 0.254)
					(thickness 0.1524)
				)
				(justify left)
			)
		)
		(property "Value" ""
			(at 0 0 90)
			(layer "F.Fab")
			(effects
				(font
					(size 1.27 1.27)
				)
			)
		)
		(duplicate_pad_numbers_are_jumpers no)
		(fp_poly
			(pts
				(xy -0.2794 -0.1016) (xy 0.2794 -0.1016) (xy 0.2794 0.9906) (xy -0.2794 0.9906)
			)
			(stroke
				(width 0)
				(type default)
			)
			(fill no)
			(layer "F.CrtYd")
		)
		(fp_line
			(start 0.2794 -0.1016)
			(end -0.2794 -0.1016)
			(stroke
				(width 0.1)
				(type default)
			)
			(layer "F.Fab")
		)
		(fp_line
			(start -0.2794 -0.1016)
			(end -0.2794 0.9906)
			(stroke
				(width 0.1)
				(type default)
			)
			(layer "F.Fab")
		)
		(fp_line
			(start 0.2794 0.9906)
			(end 0.2794 -0.1016)
			(stroke
				(width 0.1)
				(type default)
			)
			(layer "F.Fab")
		)
		(fp_line
			(start -0.2794 0.9906)
			(end 0.2794 0.9906)
			(stroke
				(width 0.1)
				(type default)
			)
			(layer "F.Fab")
		)
		(pad "1" smd rect
			(at 0 0 90)
			(size 0.508 0.508)
			(layers "F.Cu" "F.Mask" "F.Paste")
			(net "CLK_48M_USB_BMC")
		)
		(pad "2" smd rect
			(at 0 0.889 90)
			(size 0.508 0.508)
			(layers "F.Cu" "F.Mask" "F.Paste")
			(net "CLK_48M_USB_BMC_R")
		)
		(zone
			(layer "F.Cu")
			(hatch none 0.5)
			(connect_pads
				(clearance 0)
			)
			(min_thickness 0.25)
			(keepout
				(tracks allowed)
				(vias not_allowed)
				(pads allowed)
				(copperpour not_allowed)
				(footprints allowed)
			)
			(placement
				(enabled no)
				(sheetname "")
			)
			(fill
				(thermal_gap 0.5)
				(thermal_bridge_width 0.5)
				(island_removal_mode 0)
			)
			(polygon
				(pts
					(xy 404.241 -115.443) (xy 404.241 -115.951) (xy 404.622 -115.951) (xy 404.622 -115.443)
				)
			)
		)
		(zone
			(layer "F.Cu")
			(hatch none 0.5)
			(connect_pads
				(clearance 0)
			)
			(min_thickness 0.25)
			(keepout
				(tracks not_allowed)
				(vias allowed)
				(pads allowed)
				(copperpour not_allowed)
				(footprints allowed)
			)
			(placement
				(enabled no)
				(sheetname "")
			)
			(fill
				(thermal_gap 0.5)
				(thermal_bridge_width 0.5)
				(island_removal_mode 0)
			)
			(polygon
				(pts
					(xy 404.622 -115.443) (xy 404.622 -115.951) (xy 404.241 -115.951) (xy 404.241 -115.443)
				)
			)
		)
	)
	(footprint ""
		(layer "F.Cu")
		(at 370.111274 -64.113664 90)
		(property "Reference" "R7E6"
			(at 0 0 90)
			(layer "F.SilkS")
			(hide yes)
			(effects
				(font
					(size 1.27 1.27)
				)
			)
		)
		(property "Value" ""
			(at 0 0 90)
			(layer "F.Fab")
			(effects
				(font
					(size 1.27 1.27)
				)
			)
		)
		(duplicate_pad_numbers_are_jumpers no)
		(fp_poly
			(pts
				(xy -0.2794 -0.1016) (xy 0.2794 -0.1016) (xy 0.2794 0.9906) (xy -0.2794 0.9906)
			)
			(stroke
				(width 0)
				(type default)
			)
			(fill no)
			(layer "F.CrtYd")
		)
		(fp_line
			(start 0.2794 -0.1016)
			(end -0.2794 -0.1016)
			(stroke
				(width 0.1)
				(type default)
			)
			(layer "F.Fab")
		)
		(fp_line
			(start -0.2794 -0.1016)
			(end -0.2794 0.9906)
			(stroke
				(width 0.1)
				(type default)
			)
			(layer "F.Fab")
		)
		(fp_line
			(start 0.2794 0.9906)
			(end 0.2794 -0.1016)
			(stroke
				(width 0.1)
				(type default)
			)
			(layer "F.Fab")
		)
		(fp_line
			(start -0.2794 0.9906)
			(end 0.2794 0.9906)
			(stroke
				(width 0.1)
				(type default)
			)
			(layer "F.Fab")
		)
		(pad "1" smd rect
			(at 0 0 90)
			(size 0.508 0.508)
			(layers "F.Cu" "F.Mask" "F.Paste")
			(net "P3V3_STBY")
		)
		(pad "2" smd rect
			(at 0 0.889 90)
			(size 0.508 0.508)
			(layers "F.Cu" "F.Mask" "F.Paste")
			(net "PU_RST_PERST_BIT1")
		)
		(zone
			(layer "F.Cu")
			(hatch none 0.5)
			(connect_pads
				(clearance 0)
			)
			(min_thickness 0.25)
			(keepout
				(tracks allowed)
				(vias not_allowed)
				(pads allowed)
				(copperpour not_allowed)
				(footprints allowed)
			)
			(placement
				(enabled no)
				(sheetname "")
			)
			(fill
				(thermal_gap 0.5)
				(thermal_bridge_width 0.5)
				(island_removal_mode 0)
			)
			(polygon
				(pts
					(xy 370.365274 -63.859664) (xy 370.365274 -64.367664) (xy 370.746274 -64.367664) (xy 370.746274 -63.859664)
				)
			)
		)
		(zone
			(layer "F.Cu")
			(hatch none 0.5)
			(connect_pads
				(clearance 0)
			)
			(min_thickness 0.25)
			(keepout
				(tracks not_allowed)
				(vias allowed)
				(pads allowed)
				(copperpour not_allowed)
				(footprints allowed)
			)
			(placement
				(enabled no)
				(sheetname "")
			)
			(fill
				(thermal_gap 0.5)
				(thermal_bridge_width 0.5)
				(island_removal_mode 0)
			)
			(polygon
				(pts
					(xy 370.746274 -63.859664) (xy 370.746274 -64.367664) (xy 370.365274 -64.367664) (xy 370.365274 -63.859664)
				)
			)
		)
	)
)
